# BASEBOARD_FAB2 (Tioga Pass) — schematic netlist excerpt (pin names and nets, part order shuffled) for the footprints in the layout excerpt that follows; sources: Cadence DE-HDL packaged netlist, KiCad conversion of Wiwynn_Tioga_Pass_MB.brd

J9U2  SCONN288_H44441003  SCONN  pkg PIP  page 82
  \12v\(1)  = P12V_NVDIMM_GHJ
  VSS(93)  = GND
  DQ(4)  = M_J_DQ<4>
  VSS(92)  = GND
  DQ(0)  = M_J_DQ<0>
  VSS(91)  = GND
  DQS9P  = M_J_DQS_DP<9>
  DQS9N  = M_J_DQS_DN<9>
  VSS(90)  = GND
  DQ(6)  = M_J_DQ<6>
  VSS(89)  = GND
  DQ(2)  = M_J_DQ<2>
  VSS(88)  = GND
  DQ(12)  = M_J_DQ<12>
  VSS(87)  = GND
  DQ(8)  = M_J_DQ<8>
  VSS(86)  = GND
  DQS10P  = M_J_DQS_DP<10>
  DQS10N  = M_J_DQS_DN<10>
  VSS(85)  = GND
  DQ(14)  = M_J_DQ<14>
  VSS(84)  = GND
  DQ(10)  = M_J_DQ<10>
  VSS(83)  = GND
  DQ(20)  = M_J_DQ<20>
  VSS(82)  = GND
  DQ(16)  = M_J_DQ<16>
  VSS(81)  = GND
  DQS11P  = M_J_DQS_DP<11>
  DQS11N  = M_J_DQS_DN<11>
  VSS(80)  = GND
  DQ(22)  = M_J_DQ<22>
  VSS(79)  = GND
  DQ(18)  = M_J_DQ<18>
  VSS(78)  = GND
  DQ(28)  = M_J_DQ<28>
  VSS(77)  = GND
  DQ(24)  = M_J_DQ<24>
  VSS(76)  = GND
  DQS12P  = M_J_DQS_DP<12>
  DQS12N  = M_J_DQS_DN<12>
  VSS(75)  = GND
  DQ(30)  = M_J_DQ<30>
  VSS(74)  = GND
  DQ(26)  = M_J_DQ<26>
  VSS(73)  = GND
  CB(4)  = M_J_ECC<4>
  VSS(72)  = GND
  CB(0)  = M_J_ECC<0>
  VSS(71)  = GND
  DQS17P  = M_J_DQS_DP<17>
  DQS17N  = M_J_DQS_DN<17>
  VSS(70)  = GND
  CB(6)  = M_J_ECC<6>
  VSS(69)  = GND
  CB(2)  = M_J_ECC<2>
  VSS(68)  = GND
  RESET_N  = M_GHJ_RST_N
  VDD(25)  = PVDDQ_GHJ
  CKE(0)  = M_J_CKE<2>
  VDD(24)  = PVDDQ_GHJ
  ACT_N  = M_J_ACT_N
  BG(0)  = M_J_BG<0>
  VDD(23)  = PVDDQ_GHJ
  A12  = M_J_MA<12>
  A9  = M_J_MA<9>
  VDD(22)  = PVDDQ_GHJ
  A8  = M_J_MA<8>
  A6  = M_J_MA<6>
  VDD(21)  = PVDDQ_GHJ
  A3  = M_J_MA<3>
  A1  = M_J_MA<1>
  VDD(20)  = PVDDQ_GHJ
  CK0P  = M_J_CLK_DP<2>
  CK0N  = M_J_CLK_DN<2>
  VDD(19)  = PVDDQ_GHJ
  VTT(1)  = PVTT_GHJ
  EVENT_N  = FM_DIMM_EVENT_COD_N
  A0  = M_J_MA<0>
  VDD(18)  = PVDDQ_GHJ
  BA(0)  = M_J_BA<0>
  A16_RAS_N  = M_J_MA<16>
  VDD(17)  = PVDDQ_GHJ
  S0_N  = M_J_CS_N<4>
  VDD(16)  = PVDDQ_GHJ
  A15_CAS_N  = M_J_MA<15>
  ODT(0)  = M_J_ODT<2>
  VDD(15)  = PVDDQ_GHJ
  S1_N  = M_J_CS_N<5>
  VDD(14)  = PVDDQ_GHJ
  ODT(1)  = M_J_ODT<3>
  VDD(13)  = PVDDQ_GHJ
  S2_N_C(0)  = M_J_CS_N<6>
  VSS(67)  = GND
  DQ(36)  = M_J_DQ<36>
  VSS(66)  = GND
  DQ(32)  = M_J_DQ<32>
  VSS(65)  = GND
  DQS13P  = M_J_DQS_DP<13>
  DQS13N  = M_J_DQS_DN<13>
  VSS(64)  = GND
  DQ(38)  = M_J_DQ<38>
  VSS(63)  = GND
  DQ(34)  = M_J_DQ<34>
  VSS(62)  = GND
  DQ(44)  = M_J_DQ<44>
  VSS(61)  = GND
  DQ(40)  = M_J_DQ<40>
  VSS(60)  = GND
  DQS14P  = M_J_DQS_DP<14>
  DQS14N  = M_J_DQS_DN<14>
  VSS(59)  = GND
  DQ(46)  = M_J_DQ<46>
  VSS(58)  = GND
  DQ(42)  = M_J_DQ<42>
  VSS(57)  = GND
  DQ(52)  = M_J_DQ<52>
  VSS(56)  = GND
  DQ(48)  = M_J_DQ<48>
  VSS(55)  = GND
  DQS15P  = M_J_DQS_DP<15>
  DQS15N  = M_J_DQS_DN<15>
  VSS(54)  = GND
  DQ(54)  = M_J_DQ<54>
  VSS(53)  = GND
  DQ(50)  = M_J_DQ<50>
  VSS(52)  = GND
  DQ(60)  = M_J_DQ<60>
  VSS(51)  = GND
  DQ(56)  = M_J_DQ<56>
  VSS(50)  = GND
  DQS16P  = M_J_DQS_DP<16>
  DQS16N  = M_J_DQS_DN<16>
  VSS(49)  = GND
  DQ(62)  = M_J_DQ<62>
  VSS(48)  = GND
  DQ(58)  = M_J_DQ<58>
  VSS(47)  = GND
  SA(0)  = PVPP_GHJ
  SA(1)  = GND
  SCL  = SMB_DDR_GHJ_VPP_SCL
  VPP(4)  = PVPP_GHJ
  VPP(3)  = PVPP_GHJ
  RFU(2)  = TP_CH_J_DIMM_J1_RFU_2
  \12v\(0)  = P12V_NVDIMM_GHJ
  VREFCA  = M_J_VREF
  VSS(46)  = GND
  DQ(5)  = M_J_DQ<5>
  VSS(45)  = GND
  DQ(1)  = M_J_DQ<1>
  VSS(44)  = GND
  DQS0N  = M_J_DQS_DN<0>
  DQS0P  = M_J_DQS_DP<0>
  VSS(43)  = GND
  DQ(7)  = M_J_DQ<7>
  VSS(42)  = GND
  DQ(3)  = M_J_DQ<3>
  VSS(41)  = GND
  DQ(13)  = M_J_DQ<13>
  VSS(40)  = GND
  DQ(9)  = M_J_DQ<9>
  VSS(39)  = GND
  DQS1N  = M_J_DQS_DN<1>
  DQS1P  = M_J_DQS_DP<1>
  VSS(38)  = GND
  DQ(15)  = M_J_DQ<15>
  VSS(37)  = GND
  DQ(11)  = M_J_DQ<11>
  VSS(36)  = GND
  DQ(21)  = M_J_DQ<21>
  VSS(35)  = GND
  DQ(17)  = M_J_DQ<17>
  VSS(34)  = GND
  DQS2N  = M_J_DQS_DN<2>
  DQS2P  = M_J_DQS_DP<2>
  VSS(33)  = GND
  DQ(23)  = M_J_DQ<23>
  VSS(32)  = GND
  DQ(19)  = M_J_DQ<19>
  VSS(31)  = GND
  DQ(29)  = M_J_DQ<29>
  VSS(30)  = GND
  DQ(25)  = M_J_DQ<25>
  VSS(29)  = GND
  DQS3N  = M_J_DQS_DN<3>
  DQS3P  = M_J_DQS_DP<3>
  VSS(28)  = GND
  DQ(31)  = M_J_DQ<31>
  VSS(27)  = GND
  DQ(27)  = M_J_DQ<27>
  VSS(26)  = GND
  CB(5)  = M_J_ECC<5>
  VSS(25)  = GND
  CB(1)  = M_J_ECC<1>
  VSS(24)  = GND
  DQS8N  = M_J_DQS_DN<8>
  DQS8P  = M_J_DQS_DP<8>
  VSS(23)  = GND
  CB(7)  = M_J_ECC<7>
  VSS(22)  = GND
  CB(3)  = M_J_ECC<3>
  VSS(21)  = GND
  CKE(1)  = M_J_CKE<3>
  VDD(12)  = PVDDQ_GHJ
  RFU(0)  = TP_CH_J_DIMM_J1_RFU_0
  VDD(11)  = PVDDQ_GHJ
  BG(1)  = M_J_BG<1>
  ALERT_N  = M_J_ALERT_N
  VDD(10)  = PVDDQ_GHJ
  A11  = M_J_MA<11>
  A7  = M_J_MA<7>
  VDD(9)  = PVDDQ_GHJ
  A5  = M_J_MA<5>
  A4  = M_J_MA<4>
  VDD(8)  = PVDDQ_GHJ
  A2  = M_J_MA<2>
  VDD(7)  = PVDDQ_GHJ
  CK1P  = M_J_CLK_DP<3>
  CK1N  = M_J_CLK_DN<3>
  VDD(6)  = PVDDQ_GHJ
  VTT(0)  = PVTT_GHJ
  PAR  = M_J_PAR
  VDD(5)  = PVDDQ_GHJ
  BA(1)  = M_J_BA<1>
  A10  = M_J_MA<10>
  VDD(4)  = PVDDQ_GHJ
  RFU(1)  = TP_CH_J_DIMM_J1_RFU_1
  A14_WE_N  = M_J_MA<14>
  VDD(3)  = PVDDQ_GHJ
  SAVE_N_NC  = FM_ADR_COMPLETE_GHJ_N
  VDD(2)  = PVDDQ_GHJ
  A13  = M_J_MA<13>
  VDD(1)  = PVDDQ_GHJ
  A17  = M_J_MA<17>
  C(2)  = M_J_C<2>
  VDD(0)  = PVDDQ_GHJ
  S3_N_C(1)  = M_J_CS_N<7>
  SA(2)  = PVPP_GHJ
  VSS(20)  = GND
  DQ(37)  = M_J_DQ<37>
  VSS(19)  = GND
  DQ(33)  = M_J_DQ<33>
  VSS(18)  = GND
  DQS4N  = M_J_DQS_DN<4>
  DQS4P  = M_J_DQS_DP<4>
  VSS(17)  = GND
  DQ(39)  = M_J_DQ<39>
  VSS(16)  = GND
  DQ(35)  = M_J_DQ<35>
  VSS(15)  = GND
  DQ(45)  = M_J_DQ<45>
  VSS(14)  = GND
  DQ(41)  = M_J_DQ<41>
  VSS(13)  = GND
  DQS5N  = M_J_DQS_DN<5>
  DQS5P  = M_J_DQS_DP<5>
  VSS(12)  = GND
  DQ(47)  = M_J_DQ<47>
  VSS(11)  = GND
  DQ(43)  = M_J_DQ<43>
  VSS(10)  = GND
  DQ(53)  = M_J_DQ<53>
  VSS(9)  = GND
  DQ(49)  = M_J_DQ<49>
  VSS(8)  = GND
  DQS6N  = M_J_DQS_DN<6>
  DQS6P  = M_J_DQS_DP<6>
  VSS(7)  = GND
  DQ(55)  = M_J_DQ<55>
  VSS(6)  = GND
  DQ(51)  = M_J_DQ<51>
  VSS(5)  = GND
  DQ(61)  = M_J_DQ<61>
  VSS(4)  = GND
  DQ(57)  = M_J_DQ<57>
  VSS(3)  = GND
  DQS7N  = M_J_DQS_DN<7>
  DQS7P  = M_J_DQS_DP<7>
  VSS(2)  = GND
  DQ(63)  = M_J_DQ<63>
  VSS(1)  = GND
  DQ(59)  = M_J_DQ<59>
  VSS(0)  = GND
  VDDSPD  = PVPP_GHJ
  SDA  = SMB_DDR_GHJ_VPP_SDA
  VPP(1)  = PVPP_GHJ
  VPP(0)  = PVPP_GHJ
  VPP(2)  = PVPP_GHJ

(kicad_pcb
	(version 20260206)
	(generator "pcbnew")
	(generator_version "10.0")
	(general
		(thickness 1.6)
		(legacy_teardrops no)
	)
	(paper "A4")
	(title_block
		(title "Wiwynn_Tioga_Pass_MB.brd")
		(comment 1 "Tioga Pass / footprint 4543 of 4770 (J9U2), pads 1-50 of 291")
	)
	(layers
		(0 "F.Cu" signal "TOP")
		(4 "In1.Cu" signal "L2GND")
		(6 "In2.Cu" signal "L3")
		(8 "In3.Cu" signal "L4GND")
		(10 "In4.Cu" signal "L5")
		(12 "In5.Cu" signal "L6GND")
		(14 "In6.Cu" signal "L7VCC")
		(16 "In7.Cu" signal "L8VCC")
		(18 "In8.Cu" signal "L9GND")
		(20 "In9.Cu" signal "L10")
		(22 "In10.Cu" signal "L11GND")
		(24 "In11.Cu" signal "L12")
		(26 "In12.Cu" signal "L13GND")
		(2 "B.Cu" signal "BOTTOM")
		(9 "F.Adhes" user "F.Adhesive")
		(11 "B.Adhes" user "B.Adhesive")
		(13 "F.Paste" user "Package Geometry/Pastemask Top")
		(15 "B.Paste" user "Package Geometry/Pastemask Bottom")
		(5 "F.SilkS" user "Ref Des/Silkscreen Top")
		(7 "B.SilkS" user "Ref Des/Silkscreen Bottom")
		(1 "F.Mask" user "Board Geometry/Soldermask Top")
		(3 "B.Mask" user "Board Geometry/Soldermask Bottom")
		(17 "Dwgs.User" user "User.Drawings")
		(19 "Cmts.User" user "User.Comments")
		(21 "Eco1.User" user "User.Eco1")
		(23 "Eco2.User" user "User.Eco2")
		(25 "Edge.Cuts" user "Board Geometry/Outline")
		(27 "Margin" user)
		(31 "F.CrtYd" user "Package Geometry/Place Bound Top")
		(29 "B.CrtYd" user "Package Geometry/Place Bound Bottom")
		(35 "F.Fab" user "Ref Des/Assembly Top")
		(33 "B.Fab" user "Ref Des/Assembly Bottom")
	)
	(footprint ""
		(layer "B.Cu")
		(at 29.699458 -5.621782 90)
		(property "Reference" "J9U2"
			(at 2.098548 38.118542 0)
			(unlocked yes)
			(layer "B.SilkS")
			(effects
				(font
					(size 0.7874 0.5842)
					(thickness 0.1524)
				)
				(justify left mirror)
			)
		)
		(property "Value" ""
			(at 0 0 90)
			(layer "B.Fab")
			(effects
				(font
					(size 1.27 1.27)
				)
				(justify mirror)
			)
		)
		(duplicate_pad_numbers_are_jumpers no)
		(pad "" thru_hole circle
			(at -2.29997 -5.649976 270)
			(size 2.8194 2.8194)
			(drill 2.4384)
			(layers "*.Cu" "*.Mask")
			(remove_unused_layers no)
			(clearance 0.127)
			(thermal_gap 0.127)
		)
		(pad "" thru_hole oval
			(at -2.29997 68.90004 270)
			(size 2.8194 1.5748)
			(drill oval 2.4384 1.1938)
			(layers "*.Cu" "*.Mask")
			(remove_unused_layers no)
			(clearance 0.127)
			(thermal_gap 0.127)
		)
		(pad "" thru_hole circle
			(at -2.29997 132.299964 270)
			(size 2.8194 2.8194)
			(drill 2.4384)
			(layers "*.Cu" "*.Mask")
			(remove_unused_layers no)
			(clearance 0.127)
			(thermal_gap 0.127)
		)
		(pad "1" smd rect
			(at 0 0 270)
			(size 1.8034 0.508)
			(layers "B.Cu" "B.Mask" "B.Paste")
			(net "P12V_NVDIMM_GHJ")
		)
		(pad "2" smd rect
			(at 0 0.849884 270)
			(size 1.8034 0.508)
			(layers "B.Cu" "B.Mask" "B.Paste")
			(net "GND")
		)
		(pad "3" smd rect
			(at 0 1.700022 270)
			(size 1.8034 0.508)
			(layers "B.Cu" "B.Mask" "B.Paste")
			(net "M_J_DQ<4>")
		)
		(pad "4" smd rect
			(at 0 2.549906 270)
			(size 1.8034 0.508)
			(layers "B.Cu" "B.Mask" "B.Paste")
			(net "GND")
		)
		(pad "5" smd rect
			(at 0 3.400044 270)
			(size 1.8034 0.508)
			(layers "B.Cu" "B.Mask" "B.Paste")
			(net "M_J_DQ<0>")
		)
		(pad "6" smd rect
			(at 0 4.249928 270)
			(size 1.8034 0.508)
			(layers "B.Cu" "B.Mask" "B.Paste")
			(net "GND")
		)
		(pad "7" smd rect
			(at 0 5.100066 270)
			(size 1.8034 0.508)
			(layers "B.Cu" "B.Mask" "B.Paste")
			(net "M_J_DQS_DP<9>")
		)
		(pad "8" smd rect
			(at 0 5.94995 270)
			(size 1.8034 0.508)
			(layers "B.Cu" "B.Mask" "B.Paste")
			(net "M_J_DQS_DN<9>")
		)
		(pad "9" smd rect
			(at 0 6.800088 270)
			(size 1.8034 0.508)
			(layers "B.Cu" "B.Mask" "B.Paste")
			(net "GND")
		)
		(pad "10" smd rect
			(at 0 7.649972 270)
			(size 1.8034 0.508)
			(layers "B.Cu" "B.Mask" "B.Paste")
			(net "M_J_DQ<6>")
		)
		(pad "11" smd rect
			(at 0 8.50011 270)
			(size 1.8034 0.508)
			(layers "B.Cu" "B.Mask" "B.Paste")
			(net "GND")
		)
		(pad "12" smd rect
			(at 0 9.349994 270)
			(size 1.8034 0.508)
			(layers "B.Cu" "B.Mask" "B.Paste")
			(net "M_J_DQ<2>")
		)
		(pad "13" smd rect
			(at 0 10.199878 270)
			(size 1.8034 0.508)
			(layers "B.Cu" "B.Mask" "B.Paste")
			(net "GND")
		)
		(pad "14" smd rect
			(at 0 11.050016 270)
			(size 1.8034 0.508)
			(layers "B.Cu" "B.Mask" "B.Paste")
			(net "M_J_DQ<12>")
		)
		(pad "15" smd rect
			(at 0 11.8999 270)
			(size 1.8034 0.508)
			(layers "B.Cu" "B.Mask" "B.Paste")
			(net "GND")
		)
		(pad "16" smd rect
			(at 0 12.750038 270)
			(size 1.8034 0.508)
			(layers "B.Cu" "B.Mask" "B.Paste")
			(net "M_J_DQ<8>")
		)
		(pad "17" smd rect
			(at 0 13.599922 270)
			(size 1.8034 0.508)
			(layers "B.Cu" "B.Mask" "B.Paste")
			(net "GND")
		)
		(pad "18" smd rect
			(at 0 14.45006 270)
			(size 1.8034 0.508)
			(layers "B.Cu" "B.Mask" "B.Paste")
			(net "M_J_DQS_DP<10>")
		)
		(pad "19" smd rect
			(at 0 15.299944 270)
			(size 1.8034 0.508)
			(layers "B.Cu" "B.Mask" "B.Paste")
			(net "M_J_DQS_DN<10>")
		)
		(pad "20" smd rect
			(at 0 16.150082 270)
			(size 1.8034 0.508)
			(layers "B.Cu" "B.Mask" "B.Paste")
			(net "GND")
		)
		(pad "21" smd rect
			(at 0 16.999966 270)
			(size 1.8034 0.508)
			(layers "B.Cu" "B.Mask" "B.Paste")
			(net "M_J_DQ<14>")
		)
		(pad "22" smd rect
			(at 0 17.850104 270)
			(size 1.8034 0.508)
			(layers "B.Cu" "B.Mask" "B.Paste")
			(net "GND")
		)
		(pad "23" smd rect
			(at 0 18.699988 270)
			(size 1.8034 0.508)
			(layers "B.Cu" "B.Mask" "B.Paste")
			(net "M_J_DQ<10>")
		)
		(pad "24" smd rect
			(at 0 19.550126 270)
			(size 1.8034 0.508)
			(layers "B.Cu" "B.Mask" "B.Paste")
			(net "GND")
		)
		(pad "25" smd rect
			(at 0 20.40001 270)
			(size 1.8034 0.508)
			(layers "B.Cu" "B.Mask" "B.Paste")
			(net "M_J_DQ<20>")
		)
		(pad "26" smd rect
			(at 0 21.249894 270)
			(size 1.8034 0.508)
			(layers "B.Cu" "B.Mask" "B.Paste")
			(net "GND")
		)
		(pad "27" smd rect
			(at 0 22.100032 270)
			(size 1.8034 0.508)
			(layers "B.Cu" "B.Mask" "B.Paste")
			(net "M_J_DQ<16>")
		)
		(pad "28" smd rect
			(at 0 22.949916 270)
			(size 1.8034 0.508)
			(layers "B.Cu" "B.Mask" "B.Paste")
			(net "GND")
		)
		(pad "29" smd rect
			(at 0 23.800054 270)
			(size 1.8034 0.508)
			(layers "B.Cu" "B.Mask" "B.Paste")
			(net "M_J_DQS_DP<11>")
		)
		(pad "30" smd rect
			(at 0 24.649938 270)
			(size 1.8034 0.508)
			(layers "B.Cu" "B.Mask" "B.Paste")
			(net "M_J_DQS_DN<11>")
		)
		(pad "31" smd rect
			(at 0 25.500076 270)
			(size 1.8034 0.508)
			(layers "B.Cu" "B.Mask" "B.Paste")
			(net "GND")
		)
		(pad "32" smd rect
			(at 0 26.34996 270)
			(size 1.8034 0.508)
			(layers "B.Cu" "B.Mask" "B.Paste")
			(net "M_J_DQ<22>")
		)
		(pad "33" smd rect
			(at 0 27.200098 270)
			(size 1.8034 0.508)
			(layers "B.Cu" "B.Mask" "B.Paste")
			(net "GND")
		)
		(pad "34" smd rect
			(at 0 28.049982 270)
			(size 1.8034 0.508)
			(layers "B.Cu" "B.Mask" "B.Paste")
			(net "M_J_DQ<18>")
		)
		(pad "35" smd rect
			(at 0 28.90012 270)
			(size 1.8034 0.508)
			(layers "B.Cu" "B.Mask" "B.Paste")
			(net "GND")
		)
		(pad "36" smd rect
			(at 0 29.750004 270)
			(size 1.8034 0.508)
			(layers "B.Cu" "B.Mask" "B.Paste")
			(net "M_J_DQ<28>")
		)
		(pad "37" smd rect
			(at 0 30.599888 270)
			(size 1.8034 0.508)
			(layers "B.Cu" "B.Mask" "B.Paste")
			(net "GND")
		)
		(pad "38" smd rect
			(at 0 31.450026 270)
			(size 1.8034 0.508)
			(layers "B.Cu" "B.Mask" "B.Paste")
			(net "M_J_DQ<24>")
		)
		(pad "39" smd rect
			(at 0 32.29991 270)
			(size 1.8034 0.508)
			(layers "B.Cu" "B.Mask" "B.Paste")
			(net "GND")
		)
		(pad "40" smd rect
			(at 0 33.150048 270)
			(size 1.8034 0.508)
			(layers "B.Cu" "B.Mask" "B.Paste")
			(net "M_J_DQS_DP<12>")
		)
		(pad "41" smd rect
			(at 0 33.999932 270)
			(size 1.8034 0.508)
			(layers "B.Cu" "B.Mask" "B.Paste")
			(net "M_J_DQS_DN<12>")
		)
		(pad "42" smd rect
			(at 0 34.85007 270)
			(size 1.8034 0.508)
			(layers "B.Cu" "B.Mask" "B.Paste")
			(net "GND")
		)
		(pad "43" smd rect
			(at 0 35.699954 270)
			(size 1.8034 0.508)
			(layers "B.Cu" "B.Mask" "B.Paste")
			(net "M_J_DQ<30>")
		)
		(pad "44" smd rect
			(at 0 36.550092 270)
			(size 1.8034 0.508)
			(layers "B.Cu" "B.Mask" "B.Paste")
			(net "GND")
		)
		(pad "45" smd rect
			(at 0 37.399976 270)
			(size 1.8034 0.508)
			(layers "B.Cu" "B.Mask" "B.Paste")
			(net "M_J_DQ<26>")
		)
		(pad "46" smd rect
			(at 0 38.250114 270)
			(size 1.8034 0.508)
			(layers "B.Cu" "B.Mask" "B.Paste")
			(net "GND")
		)
		(pad "47" smd rect
			(at 0 39.099998 270)
			(size 1.8034 0.508)
			(layers "B.Cu" "B.Mask" "B.Paste")
			(net "M_J_ECC<4>")
		)
	)
)
